FILE_TYPE = CONNECTIVITY;
{Allegro Design Entry HDL 16.6-p007 (v16-6-112F) 10/10/2012}
"PAGE_NUMBER" = 104;
0"NC";
1"P3V3\g";
2"GND\g";
3"GND\g";
4"GND\g";
5"P3V3\g";
6"GND\g";
7"CLK_156M_OSC_CPU0_HFI_DP";
8"CLK_322M_OSC_CPU0_RC_DN";
9"CLK_322M_OSC_CPU0_RC_DP";
10"CLK_156M_OSC_CPU0_HFI_DN";
11"CLK_322M_156M_CPU0_OSC_VRM_DN";
12"CLK_322M_156M_CPU0_OSC_VRM_DP";
13"CLK_156M_OSC_CPU1_HFI_DN";
14"CLK_156M_OSC_CPU1_HFI_DP";
15"FM_CPU0_STL_BRD_OSC_EN";
16"CLK_322M_OSC_CPU1_RC_DN";
17"CLK_322M_OSC_CPU1_RC_DP";
18"CLK_322M_156M_CPU1_OSC_VRM_DN";
19"CLK_322M_156M_CPU1_OSC_VRM_DP";
20"FM_CPU1_STL_BRD_OSC_EN";
21"FM_CPU1_VRM_322M_156M_OSC_EN";
22"FM_CPU0_VRM_322M_156M_OSC_EN";
23"FM_CPU0_VRM_OSC_EN";
24"FM_CPU1_VRM_OSC_EN";
25"CLK_156M_OSC_BRD_CPU1_DP";
26"CLK_156M_OSC_BRD_CPU0_DP";
27"FM_156M_CPU1_BRD_OSC_EN";
28"CLK_156M_OSC_BRD_CPU1_DN";
29"FM_156M_CPU0_BRD_OSC_EN";
30"CLK_156M_OSC_BRD_CPU0_DN";
31"CLK_156M_OSC_BRD_CPU0_DN";
32"CLK_156M_OSC_BRD_CPU0_DP";
33"CLK_156M_OSC_BRD_CPU1_DN";
34"CLK_156M_OSC_BRD_CPU1_DP";
35"FM_CPU0_STL_BRD_OSC_EN";
36"NC_CLK_156M_CPU0_OSC";
37"FM_CPU1_STL_BRD_OSC_EN";
38"NC_CLK_156M_CPU1_OSC";
%"P3V3"
"1","(-3975,5350)","0","mstr_symbols","I24";
;
SIZE"1B"
CDS_LIB"mstr_symbols"
VOLTAGE"3.3V"
BODY_TYPE"PLUMBING"
HDL_POWER"P3V3";
"G\NAC"1;
%"CAP_A"
"1","(-4250,5100)","0","dev_discrete","I25";
;
CDS_LOCATION"C6F1"
SEC"1"
SEC_TYPE"0402V"
CDS_SEC"1"
ROOM"CLOCK_CPU0_OSC"
CDS_LIB"dev_discrete"
VALUE"0.1UF"
PACK_TYPE"0402V"
PART_NUMBER"A36096-030"
LOCATION"C6F1"
VOLTAGE"16V"
MATERIAL"X7R"
TOLERANCE"10%";
"B"
$PN"2"3;
"A"
$PN"1"1;
%"GND"
"1","(-2725,4550)","0","mstr_symbols","I26";
;
HDL_POWER"GND"
VOLTAGE"0.0V"
CDS_LIB"mstr_symbols"
BODY_TYPE"PLUMBING"
SIZE"1B";
"A\NAC"2;
%"GND"
"1","(-4250,4900)","0","mstr_symbols","I27";
;
HDL_POWER"GND"
CDS_LIB"mstr_symbols"
VOLTAGE"0.0V"
BODY_TYPE"PLUMBING"
SIZE"1B";
"A\NAC"3;
%"GND"
"1","(-3050,3700)","0","mstr_symbols","I31";
;
HDL_POWER"GND"
SIZE"1B"
CDS_LIB"mstr_symbols"
BODY_TYPE"PLUMBING"
VOLTAGE"0.0V";
"A\NAC"4;
%"P3V3"
"1","(-4275,4475)","0","mstr_symbols","I32";
;
SIZE"1B"
CDS_LIB"mstr_symbols"
VOLTAGE"3.3V"
BODY_TYPE"PLUMBING"
HDL_POWER"P3V3";
"G\NAC"5;
%"GND"
"1","(-4575,4025)","0","mstr_symbols","I33";
;
HDL_POWER"GND"
SIZE"1B"
CDS_LIB"mstr_symbols"
VOLTAGE"0.0V"
BODY_TYPE"PLUMBING";
"A\NAC"6;
%"CAP_A"
"1","(-4575,4225)","0","dev_discrete","I34";
;
CDS_SEC"1"
SEC"1"
SEC_TYPE"0402V"
ROOM"CLOCK_CPU1_OSC"
CDS_LIB"dev_discrete"
CDS_LOCATION"C3F2"
VOLTAGE"16V"
LOCATION"C3F2"
VALUE"0.1UF"
TOLERANCE"10%"
MATERIAL"X7R"
PART_NUMBER"A36096-030"
PACK_TYPE"0402V";
"B"
$PN"2"6;
"A"
$PN"1"5;
%"RES"
"1","(525,4300)","0","mstr_discrete","I37";
;
CDS_SEC"1"
ROOM"CLOCK_CPU0_OSC"
CDS_LIB"mstr_discrete"
NO_XNET_CONNECTION"1"
SEC"1"
SEC_TYPE"0402"
CDS_LOCATION"R6F8"
PART_NUMBER"G21497-005"
PACK_TYPE"0402"
MATERIAL"EMPTY"
TOLERANCE"5%"
LOCATION"R6F8"
WATTAGE"1/16W"
VALUE"0.0";
"B"
$PN"2"7;
"A"
$PN"1"12;
%"RES"
"1","(525,4950)","0","mstr_discrete","I41";
;
CDS_SEC"1"
SEC_TYPE"0402"
SEC"1"
NO_XNET_CONNECTION"1"
ROOM"CLOCK_CPU0_OSC"
CDS_LIB"mstr_discrete"
CDS_LOCATION"R6F6"
PART_NUMBER"G21497-005"
PACK_TYPE"0402"
MATERIAL"EMPTY"
LOCATION"R6F6"
TOLERANCE"5%"
WATTAGE"1/16W"
VALUE"0.0";
"B"
$PN"2"10;
"A"
$PN"1"11;
%"RES"
"1","(525,3575)","0","mstr_discrete","I51";
;
CDS_SEC"1"
ROOM"CLOCK_CPU1_OSC"
CDS_LIB"mstr_discrete"
SEC_TYPE"0402"
NO_XNET_CONNECTION"1"
SEC"1"
CDS_LOCATION"R3F1"
PART_NUMBER"G21497-005"
PACK_TYPE"0402"
MATERIAL"EMPTY"
LOCATION"R3F1"
TOLERANCE"5%"
WATTAGE"1/16W"
VALUE"0.0";
"B"
$PN"2"13;
"A"
$PN"1"18;
%"RES"
"1","(525,2875)","0","mstr_discrete","I53";
;
CDS_SEC"1"
SEC_TYPE"0402"
SEC"1"
NO_XNET_CONNECTION"1"
ROOM"CLOCK_CPU1_OSC"
CDS_LIB"mstr_discrete"
CDS_LOCATION"R3F3"
PART_NUMBER"G21497-005"
PACK_TYPE"0402"
MATERIAL"EMPTY"
LOCATION"R3F3"
TOLERANCE"5%"
WATTAGE"1/16W"
VALUE"0.0";
"B"
$PN"2"14;
"A"
$PN"1"19;
%"RES"
"1","(525,5150)","0","mstr_discrete","I67";
;
CDS_SEC"1"
CDS_LIB"mstr_discrete"
SEC_TYPE"0402"
SEC"1"
CDS_LOCATION"R6F7"
ROOM"CLOCK_CPU0_OSC"
NO_XNET_CONNECTION"1"
PART_NUMBER"G21497-005"
LOCATION"R6F7"
VALUE"0.0"
PACK_TYPE"0402"
WATTAGE"1/16W"
TOLERANCE"5%"
MATERIAL"CHIP";
"B"
$PN"2"10;
"A"
$PN"1"30;
%"RES"
"1","(525,4500)","0","mstr_discrete","I68";
;
CDS_SEC"1"
CDS_LIB"mstr_discrete"
SEC_TYPE"0402"
NO_XNET_CONNECTION"1"
SEC"1"
ROOM"CLOCK_CPU0_OSC"
CDS_LOCATION"R6F9"
PART_NUMBER"G21497-005"
PACK_TYPE"0402"
MATERIAL"CHIP"
LOCATION"R6F9"
TOLERANCE"5%"
WATTAGE"1/16W"
VALUE"0.0";
"B"
$PN"2"7;
"A"
$PN"1"26;
%"RES"
"1","(525,3775)","0","mstr_discrete","I69";
;
CDS_SEC"1"
CDS_LIB"mstr_discrete"
SEC_TYPE"0402"
SEC"1"
ROOM"CLOCK_CPU1_OSC"
NO_XNET_CONNECTION"1"
CDS_LOCATION"R3F2"
PART_NUMBER"G21497-005"
PACK_TYPE"0402"
MATERIAL"CHIP"
LOCATION"R3F2"
TOLERANCE"5%"
WATTAGE"1/16W"
VALUE"0.0";
"B"
$PN"2"13;
"A"
$PN"1"28;
%"RES"
"1","(525,3075)","0","mstr_discrete","I70";
;
CDS_SEC"1"
CDS_LIB"mstr_discrete"
SEC_TYPE"0402"
SEC"1"
ROOM"CLOCK_CPU1_OSC"
NO_XNET_CONNECTION"1"
CDS_LOCATION"R3F4"
PART_NUMBER"G21497-005"
LOCATION"R3F4"
PACK_TYPE"0402"
MATERIAL"CHIP"
TOLERANCE"5%"
WATTAGE"1/16W"
VALUE"0.0";
"B"
$PN"2"14;
"A"
$PN"1"25;
%"OSC_C"
"17","(-3400,4775)","0","mstr_discrete","I71";
;
CDS_SEC"1"
PACK_TYPE"6P10"
SEC"1"
SEC_TYPE"6P10"
CDS_LOCATION"Y6F1"
CDS_LIB"mstr_discrete"
CDS_LMAN_SYM_OUTLINE"-450,200,450,-200"
LOCATION"Y6F1"
PART_NUMBER"G63831-004"
MATERIAL"OSC"
VALUE"156.25MHZ";
"ENABLE_DISABLE"
$PN"1"35;
"OUT"
$PN"4"32;
"GND"
$PN"3"2;
"VCC"
$PN"6"1;
"OUT_N \B"
$PN"5"31;
"NC_GND"
$PN"2"36;
%"OSC_C"
"17","(-3700,3925)","0","mstr_discrete","I72";
;
CDS_SEC"1"
CDS_LMAN_SYM_OUTLINE"-450,200,450,-200"
CDS_LIB"mstr_discrete"
PACK_TYPE"6P10"
SEC_TYPE"6P10"
CDS_LOCATION"Y3F1"
SEC"1"
LOCATION"Y3F1"
PART_NUMBER"G63831-004"
VALUE"156.25MHZ"
MATERIAL"OSC";
"ENABLE_DISABLE"
$PN"1"37;
"OUT"
$PN"4"34;
"GND"
$PN"3"4;
"VCC"
$PN"6"5;
"OUT_N \B"
$PN"5"33;
"NC_GND"
$PN"2"38;
%"RES"
"1","(525,4750)","0","mstr_discrete","I78";
;
CDS_SEC"1"
CDS_LOCATION"R6F10"
CDS_LIB"mstr_discrete"
SEC_TYPE"0402"
SEC"1"
PART_NUMBER"G21497-005"
PACK_TYPE"0402"
MATERIAL"EMPTY"
LOCATION"R6F10"
TOLERANCE"5%"
WATTAGE"1/16W"
VALUE"0.0";
"B"
$PN"2"8;
"A"
$PN"1"11;
%"RES"
"1","(525,4100)","0","mstr_discrete","I79";
;
CDS_SEC"1"
CDS_LOCATION"R6F11"
CDS_LIB"mstr_discrete"
SEC_TYPE"0402"
SEC"1"
PART_NUMBER"G21497-005"
LOCATION"R6F11"
PACK_TYPE"0402"
MATERIAL"EMPTY"
TOLERANCE"5%"
VALUE"0.0"
WATTAGE"1/16W";
"B"
$PN"2"9;
"A"
$PN"1"12;
%"RES"
"1","(525,3375)","0","mstr_discrete","I84";
;
CDS_SEC"1"
CDS_LOCATION"R3F5"
CDS_LIB"mstr_discrete"
SEC_TYPE"0402"
SEC"1"
PART_NUMBER"G21497-005"
PACK_TYPE"0402"
MATERIAL"EMPTY"
TOLERANCE"5%"
LOCATION"R3F5"
VALUE"0.0"
WATTAGE"1/16W";
"B"
$PN"2"16;
"A"
$PN"1"18;
%"RES"
"1","(525,2675)","0","mstr_discrete","I88";
;
CDS_SEC"1"
CDS_LOCATION"R3F6"
CDS_LIB"mstr_discrete"
SEC_TYPE"0402"
SEC"1"
PACK_TYPE"0402"
PART_NUMBER"G21497-005"
MATERIAL"EMPTY"
TOLERANCE"5%"
LOCATION"R3F6"
WATTAGE"1/16W"
VALUE"0.0";
"B"
$PN"2"17;
"A"
$PN"1"19;
%"RES"
"1","(550,2200)","0","mstr_discrete","I93";
;
CDS_SEC"1"
CDS_LOCATION"R8D43"
CDS_LIB"mstr_discrete"
SEC_TYPE"0402"
SEC"1"
ROOM"CLOCK_CPU1_OSC"
PART_NUMBER"G21497-005"
PACK_TYPE"0402"
MATERIAL"CHIP"
TOLERANCE"5%"
LOCATION"R8D43"
WATTAGE"1/16W"
VALUE"0.0";
"B"
$PN"2"15;
"A"
$PN"1"29;
%"RES"
"1","(550,2000)","0","mstr_discrete","I94";
;
CDS_SEC"1"
CDS_LOCATION"R7D40"
ROOM"CLOCK_CPU1_OSC"
SEC_TYPE"0402"
SEC"1"
CDS_LIB"mstr_discrete"
LOCATION"R7D40"
PART_NUMBER"G21497-005"
PACK_TYPE"0402"
MATERIAL"EMPTY"
TOLERANCE"5%"
WATTAGE"1/16W"
VALUE"0.0";
"B"
$PN"2"15;
"A"
$PN"1"23;
%"RES"
"1","(550,1800)","0","mstr_discrete","I95";
;
CDS_SEC"1"
CDS_LOCATION"R7D39"
CDS_LIB"mstr_discrete"
SEC_TYPE"0402"
SEC"1"
PART_NUMBER"G21497-005"
PACK_TYPE"0402"
MATERIAL"EMPTY"
TOLERANCE"5%"
WATTAGE"1/16W"
LOCATION"R7D39"
VALUE"0.0";
"B"
$PN"2"22;
"A"
$PN"1"23;
%"RES"
"1","(550,1500)","0","mstr_discrete","I96";
;
CDS_SEC"1"
CDS_LOCATION"R7D36"
CDS_LIB"mstr_discrete"
SEC_TYPE"0402"
SEC"1"
ROOM"CLOCK_CPU1_OSC"
PART_NUMBER"G21497-005"
PACK_TYPE"0402"
MATERIAL"CHIP"
TOLERANCE"5%"
LOCATION"R7D36"
WATTAGE"1/16W"
VALUE"0.0";
"B"
$PN"2"20;
"A"
$PN"1"27;
%"RES"
"1","(550,1300)","0","mstr_discrete","I97";
;
CDS_SEC"1"
CDS_LOCATION"R7D38"
ROOM"CLOCK_CPU1_OSC"
CDS_LIB"mstr_discrete"
SEC_TYPE"0402"
SEC"1"
PART_NUMBER"G21497-005"
PACK_TYPE"0402"
MATERIAL"EMPTY"
TOLERANCE"5%"
LOCATION"R7D38"
WATTAGE"1/16W"
VALUE"0.0";
"B"
$PN"2"20;
"A"
$PN"1"24;
%"RES"
"1","(550,1100)","0","mstr_discrete","I98";
;
CDS_SEC"1"
CDS_LOCATION"R7D37"
CDS_LIB"mstr_discrete"
SEC_TYPE"0402"
SEC"1"
PART_NUMBER"G21497-005"
PACK_TYPE"0402"
MATERIAL"EMPTY"
TOLERANCE"5%"
LOCATION"R7D37"
WATTAGE"1/16W"
VALUE"0.0";
"B"
$PN"2"21;
"A"
$PN"1"24;
END.
